(kicad_pcb
	(version 20260206)
	(generator "pcbnew")
	(generator_version "10.0")
	(general
		(thickness 1.6)
		(legacy_teardrops no)
	)
	(paper "A4")
	(title_block
		(title "netronome-mezz — pcbd0082-001_rev01_jul9_a.brd")
		(comment 1 "Open CloudServer (Microsoft) / footprints 515-523 of 714")
	)
	(layers
		(0 "F.Cu" signal "TOP")
		(4 "In1.Cu" signal "02_GND")
		(6 "In2.Cu" signal "03_SIG")
		(8 "In3.Cu" signal "04_SIG")
		(10 "In4.Cu" signal "05_GND")
		(12 "In5.Cu" signal "06_PWR1")
		(14 "In6.Cu" signal "07_SIG")
		(16 "In7.Cu" signal "08_SIG")
		(18 "In8.Cu" signal "09_GND")
		(2 "B.Cu" signal "BOTTOM")
		(9 "F.Adhes" user "F.Adhesive")
		(11 "B.Adhes" user "B.Adhesive")
		(13 "F.Paste" user "Package Geometry/Pastemask Top")
		(15 "B.Paste" user "Package Geometry/Pastemask Bottom")
		(5 "F.SilkS" user "Ref Des/Silkscreen Top")
		(7 "B.SilkS" user "Ref Des/Silkscreen Bottom")
		(1 "F.Mask" user "Board Geometry/Soldermask Top")
		(3 "B.Mask" user "Board Geometry/Soldermask Bottom")
		(17 "Dwgs.User" user "User.Drawings")
		(19 "Cmts.User" user "User.Comments")
		(21 "Eco1.User" user "User.Eco1")
		(23 "Eco2.User" user "User.Eco2")
		(25 "Edge.Cuts" user "Board Geometry/Outline")
		(27 "Margin" user)
		(31 "F.CrtYd" user "Package Geometry/Place Bound Top")
		(29 "B.CrtYd" user "Package Geometry/Place Bound Bottom")
		(35 "F.Fab" user "Ref Des/Assembly Top")
		(33 "B.Fab" user "Ref Des/Assembly Bottom")
		(45 "User.4" user "COMPVAL_TYPE_BOTTOM")
	)
	(footprint ""
		(layer "B.Cu")
		(at 56.236997 9.542018)
		(property "Reference" "C30"
			(at 0 0 0)
			(layer "B.SilkS")
			(hide yes)
			(effects
				(font
					(size 1.27 1.27)
				)
				(justify mirror)
			)
		)
		(property "Value" ""
			(at 0 0 0)
			(layer "B.Fab")
			(effects
				(font
					(size 1.27 1.27)
				)
				(justify mirror)
			)
		)
		(duplicate_pad_numbers_are_jumpers no)
		(fp_circle
			(center 0 0)
			(end 0.104648 0)
			(stroke
				(width 0.1016)
				(type default)
			)
			(fill no)
			(layer "B.SilkS")
		)
		(fp_poly
			(pts
				(xy 0.381 -0.889) (xy 0.381 0.889) (xy -0.381 0.889) (xy -0.381 -0.889)
			)
			(stroke
				(width 0)
				(type default)
			)
			(fill no)
			(layer "B.CrtYd")
		)
		(fp_line
			(start -0.508 -1.016)
			(end -0.508 1.016)
			(stroke
				(width 0.0254)
				(type default)
			)
			(layer "B.Fab")
		)
		(fp_line
			(start -0.508 1.016)
			(end 0.508 1.016)
			(stroke
				(width 0.0254)
				(type default)
			)
			(layer "B.Fab")
		)
		(fp_line
			(start 0.254 -1.016)
			(end -0.508 -1.016)
			(stroke
				(width 0.0254)
				(type default)
			)
			(layer "B.Fab")
		)
		(fp_line
			(start 0.508 -1.016)
			(end 0.254 -1.016)
			(stroke
				(width 0.0254)
				(type default)
			)
			(layer "B.Fab")
		)
		(fp_line
			(start 0.508 1.016)
			(end 0.508 -1.016)
			(stroke
				(width 0.0254)
				(type default)
			)
			(layer "B.Fab")
		)
		(pad "1" smd custom
			(at 0 -0.500126 180)
			(size 0.127 0.127)
			(layers "B.Cu" "B.Mask" "B.Paste")
			(net "VDDAH_PCIE0")
			(options
				(clearance outline)
				(anchor circle)
			)
			(primitives
				(gr_poly
					(pts
						(xy -0.1778 0.254) (xy 0.1778 0.254) (xy 0.254 0.1778) (xy 0.254 -0.1778) (xy 0.1778 -0.254) (xy -0.1778 -0.254)
						(xy -0.254 -0.1778) (xy -0.254 0.1778)
					)
					(width 0)
					(fill yes)
				)
			)
		)
		(pad "2" smd custom
			(at 0 0.500126 180)
			(size 0.127 0.127)
			(layers "B.Cu" "B.Mask" "B.Paste")
			(net "GND")
			(options
				(clearance outline)
				(anchor circle)
			)
			(primitives
				(gr_poly
					(pts
						(xy -0.1778 0.254) (xy 0.1778 0.254) (xy 0.254 0.1778) (xy 0.254 -0.1778) (xy 0.1778 -0.254) (xy -0.1778 -0.254)
						(xy -0.254 -0.1778) (xy -0.254 0.1778)
					)
					(width 0)
					(fill yes)
				)
			)
		)
	)
	(footprint ""
		(layer "B.Cu")
		(at 40.259 37.846)
		(property "Reference" "TP34"
			(at -1.143 -0.73533 0)
			(unlocked yes)
			(layer "B.SilkS")
			(effects
				(font
					(size 0.7874 0.5842)
					(thickness 0.127)
				)
				(justify left mirror)
			)
		)
		(property "Value" "*"
			(at 0.4826 -0.14732 0)
			(unlocked yes)
			(layer "B.Fab")
			(hide yes)
			(effects
				(font
					(size 1.27 0.9652)
					(thickness 0.000001)
				)
				(justify left mirror)
			)
		)
		(property "Device Type" "TP_SMALL"
			(at 0.4826 -0.14732 0)
			(unlocked yes)
			(layer "B.Fab")
			(hide yes)
			(effects
				(font
					(size 1.27 0.9652)
					(thickness 0.000001)
				)
				(justify left mirror)
			)
		)
		(duplicate_pad_numbers_are_jumpers no)
		(fp_line
			(start -0.8636 -0.8636)
			(end 0.8636 -0.8636)
			(stroke
				(width 0.1524)
				(type default)
			)
			(layer "B.SilkS")
		)
		(fp_line
			(start -0.8636 0.8636)
			(end -0.8636 -0.8636)
			(stroke
				(width 0.1524)
				(type default)
			)
			(layer "B.SilkS")
		)
		(fp_line
			(start 0.8636 -0.8636)
			(end 0.8636 0.8636)
			(stroke
				(width 0.1524)
				(type default)
			)
			(layer "B.SilkS")
		)
		(fp_line
			(start 0.8636 0.8636)
			(end -0.8636 0.8636)
			(stroke
				(width 0.1524)
				(type default)
			)
			(layer "B.SilkS")
		)
		(fp_poly
			(pts
				(xy 0.635 -0.635) (xy 0.635 0.635) (xy -0.635 0.635) (xy -0.635 -0.635)
			)
			(stroke
				(width 0)
				(type default)
			)
			(fill no)
			(layer "B.CrtYd")
		)
		(pad "1" smd rect
			(at 0 0 180)
			(size 1.27 1.27)
			(layers "B.Cu" "B.Mask" "B.Paste")
			(net "CORE_FB_PH2_THERM_L")
		)
	)
	(footprint ""
		(layer "B.Cu")
		(at 78.650998 2.699004)
		(property "Reference" "V1_A-RAS"
			(at 0 0 0)
			(layer "B.SilkS")
			(hide yes)
			(effects
				(font
					(size 1.27 1.27)
				)
				(justify mirror)
			)
		)
		(property "Value" ""
			(at 0 0 0)
			(layer "B.Fab")
			(effects
				(font
					(size 1.27 1.27)
				)
				(justify mirror)
			)
		)
		(duplicate_pad_numbers_are_jumpers no)
		(pad "1" thru_hole circle
			(at 0 0 180)
			(size 0.4572 0.4572)
			(drill 0.20574)
			(layers "*.Cu" "*.Mask")
			(remove_unused_layers no)
			(net "DDR0_32A_RAS_L")
			(clearance 0.1143)
			(thermal_gap 0.1143)
		)
	)
	(footprint ""
		(layer "B.Cu")
		(at 52.237005 13.54201)
		(property "Reference" "C162"
			(at 0 0 0)
			(layer "B.SilkS")
			(hide yes)
			(effects
				(font
					(size 1.27 1.27)
				)
				(justify mirror)
			)
		)
		(property "Value" ""
			(at 0 0 0)
			(layer "B.Fab")
			(effects
				(font
					(size 1.27 1.27)
				)
				(justify mirror)
			)
		)
		(duplicate_pad_numbers_are_jumpers no)
		(fp_circle
			(center 0 0)
			(end 0.104648 0)
			(stroke
				(width 0.1016)
				(type default)
			)
			(fill no)
			(layer "B.SilkS")
		)
		(fp_poly
			(pts
				(xy 0.381 -0.889) (xy 0.381 0.889) (xy -0.381 0.889) (xy -0.381 -0.889)
			)
			(stroke
				(width 0)
				(type default)
			)
			(fill no)
			(layer "B.CrtYd")
		)
		(fp_line
			(start -0.508 -1.016)
			(end -0.508 1.016)
			(stroke
				(width 0.0254)
				(type default)
			)
			(layer "B.Fab")
		)
		(fp_line
			(start -0.508 1.016)
			(end 0.508 1.016)
			(stroke
				(width 0.0254)
				(type default)
			)
			(layer "B.Fab")
		)
		(fp_line
			(start 0.254 -1.016)
			(end -0.508 -1.016)
			(stroke
				(width 0.0254)
				(type default)
			)
			(layer "B.Fab")
		)
		(fp_line
			(start 0.508 -1.016)
			(end 0.254 -1.016)
			(stroke
				(width 0.0254)
				(type default)
			)
			(layer "B.Fab")
		)
		(fp_line
			(start 0.508 1.016)
			(end 0.508 -1.016)
			(stroke
				(width 0.0254)
				(type default)
			)
			(layer "B.Fab")
		)
		(pad "1" smd custom
			(at 0 -0.500126 180)
			(size 0.127 0.127)
			(layers "B.Cu" "B.Mask" "B.Paste")
			(net "VDD_CORE")
			(options
				(clearance outline)
				(anchor circle)
			)
			(primitives
				(gr_poly
					(pts
						(xy -0.1778 0.254) (xy 0.1778 0.254) (xy 0.254 0.1778) (xy 0.254 -0.1778) (xy 0.1778 -0.254) (xy -0.1778 -0.254)
						(xy -0.254 -0.1778) (xy -0.254 0.1778)
					)
					(width 0)
					(fill yes)
				)
			)
		)
		(pad "2" smd custom
			(at 0 0.500126 180)
			(size 0.127 0.127)
			(layers "B.Cu" "B.Mask" "B.Paste")
			(net "GND")
			(options
				(clearance outline)
				(anchor circle)
			)
			(primitives
				(gr_poly
					(pts
						(xy -0.1778 0.254) (xy 0.1778 0.254) (xy 0.254 0.1778) (xy 0.254 -0.1778) (xy 0.1778 -0.254) (xy -0.1778 -0.254)
						(xy -0.254 -0.1778) (xy -0.254 0.1778)
					)
					(width 0)
					(fill yes)
				)
			)
		)
	)
	(footprint ""
		(layer "B.Cu")
		(at 54.737 30.8356)
		(property "Reference" "C13"
			(at -1.16967 1.2573 270)
			(unlocked yes)
			(layer "B.SilkS")
			(effects
				(font
					(size 0.7874 0.5842)
					(thickness 0.127)
				)
				(justify left mirror)
			)
		)
		(property "Value" "22UF"
			(at 0.148158 1.7526 270)
			(unlocked yes)
			(layer "B.Fab")
			(hide yes)
			(effects
				(font
					(size 1.27 0.9652)
					(thickness 0.000001)
				)
				(justify left mirror)
			)
		)
		(property "Device Type" "CAPC0063"
			(at 0.148158 1.7526 270)
			(unlocked yes)
			(layer "B.Fab")
			(hide yes)
			(effects
				(font
					(size 1.27 0.9652)
					(thickness 0.000001)
				)
				(justify left mirror)
			)
		)
		(duplicate_pad_numbers_are_jumpers no)
		(fp_circle
			(center 0 0)
			(end 0.127 0)
			(stroke
				(width 0.2032)
				(type default)
			)
			(fill no)
			(layer "B.SilkS")
		)
		(fp_poly
			(pts
				(xy -0.7874 -1.6637) (xy 0.7874 -1.6637) (xy 0.7874 1.6637) (xy -0.7874 1.6637)
			)
			(stroke
				(width 0)
				(type default)
			)
			(fill no)
			(layer "B.CrtYd")
		)
		(fp_line
			(start -0.4064 -0.7874)
			(end -0.4064 0.8128)
			(stroke
				(width 0.0254)
				(type default)
			)
			(layer "B.Fab")
		)
		(fp_line
			(start -0.4064 0.8128)
			(end 0.4064 0.8128)
			(stroke
				(width 0.0254)
				(type default)
			)
			(layer "B.Fab")
		)
		(fp_line
			(start 0.4064 -0.7874)
			(end -0.4064 -0.7874)
			(stroke
				(width 0.0254)
				(type default)
			)
			(layer "B.Fab")
		)
		(fp_line
			(start 0.4064 0.8128)
			(end 0.4064 -0.7874)
			(stroke
				(width 0.0254)
				(type default)
			)
			(layer "B.Fab")
		)
		(pad "1" smd rect
			(at 0 -0.8001 180)
			(size 0.8636 0.9652)
			(layers "B.Cu" "B.Mask" "B.Paste")
			(net "VDD_CORE")
		)
		(pad "2" smd rect
			(at 0 0.8001 180)
			(size 0.8636 0.9652)
			(layers "B.Cu" "B.Mask" "B.Paste")
			(net "GND")
		)
		(zone
			(layer "B.Cu")
			(hatch none 0.5)
			(connect_pads
				(clearance 0)
			)
			(min_thickness 0.25)
			(keepout
				(tracks not_allowed)
				(vias allowed)
				(pads allowed)
				(copperpour not_allowed)
				(footprints allowed)
			)
			(placement
				(enabled no)
				(sheetname "")
			)
			(fill
				(thermal_gap 0.5)
				(thermal_bridge_width 0.5)
				(island_removal_mode 0)
			)
			(polygon
				(pts
					(xy 54.8005 30.5816) (xy 54.6735 30.5816) (xy 54.6735 31.0896) (xy 54.8005 31.0896)
				)
			)
		)
	)
	(footprint ""
		(layer "B.Cu")
		(at 56.736996 7.042023 90)
		(property "Reference" "C38"
			(at 0 0 90)
			(layer "B.SilkS")
			(hide yes)
			(effects
				(font
					(size 1.27 1.27)
				)
				(justify mirror)
			)
		)
		(property "Value" ""
			(at 0 0 90)
			(layer "B.Fab")
			(effects
				(font
					(size 1.27 1.27)
				)
				(justify mirror)
			)
		)
		(duplicate_pad_numbers_are_jumpers no)
		(fp_circle
			(center 0 0)
			(end 0 0.104648)
			(stroke
				(width 0.1016)
				(type default)
			)
			(fill no)
			(layer "B.SilkS")
		)
		(fp_poly
			(pts
				(xy 0.381 -0.889) (xy 0.381 0.889) (xy -0.381 0.889) (xy -0.381 -0.889)
			)
			(stroke
				(width 0)
				(type default)
			)
			(fill no)
			(layer "B.CrtYd")
		)
		(fp_line
			(start 0.508 -1.016)
			(end 0.254 -1.016)
			(stroke
				(width 0.0254)
				(type default)
			)
			(layer "B.Fab")
		)
		(fp_line
			(start 0.254 -1.016)
			(end -0.508 -1.016)
			(stroke
				(width 0.0254)
				(type default)
			)
			(layer "B.Fab")
		)
		(fp_line
			(start -0.508 -1.016)
			(end -0.508 1.016)
			(stroke
				(width 0.0254)
				(type default)
			)
			(layer "B.Fab")
		)
		(fp_line
			(start 0.508 1.016)
			(end 0.508 -1.016)
			(stroke
				(width 0.0254)
				(type default)
			)
			(layer "B.Fab")
		)
		(fp_line
			(start -0.508 1.016)
			(end 0.508 1.016)
			(stroke
				(width 0.0254)
				(type default)
			)
			(layer "B.Fab")
		)
		(pad "1" smd custom
			(at 0 -0.500126 270)
			(size 0.127 0.127)
			(layers "B.Cu" "B.Mask" "B.Paste")
			(net "VDDAH_PCIE0")
			(options
				(clearance outline)
				(anchor circle)
			)
			(primitives
				(gr_poly
					(pts
						(xy -0.1778 0.254) (xy 0.1778 0.254) (xy 0.254 0.1778) (xy 0.254 -0.1778) (xy 0.1778 -0.254) (xy -0.1778 -0.254)
						(xy -0.254 -0.1778) (xy -0.254 0.1778)
					)
					(width 0)
					(fill yes)
				)
			)
		)
		(pad "2" smd custom
			(at 0 0.500126 270)
			(size 0.127 0.127)
			(layers "B.Cu" "B.Mask" "B.Paste")
			(net "GND")
			(options
				(clearance outline)
				(anchor circle)
			)
			(primitives
				(gr_poly
					(pts
						(xy -0.1778 0.254) (xy 0.1778 0.254) (xy 0.254 0.1778) (xy 0.254 -0.1778) (xy 0.1778 -0.254) (xy -0.1778 -0.254)
						(xy -0.254 -0.1778) (xy -0.254 0.1778)
					)
					(width 0)
					(fill yes)
				)
			)
		)
	)
	(footprint ""
		(layer "B.Cu")
		(at 44.237021 11.542014 180)
		(property "Reference" "C276"
			(at 0 0 0)
			(layer "B.SilkS")
			(hide yes)
			(effects
				(font
					(size 1.27 1.27)
				)
				(justify mirror)
			)
		)
		(property "Value" ""
			(at 0 0 0)
			(layer "B.Fab")
			(effects
				(font
					(size 1.27 1.27)
				)
				(justify mirror)
			)
		)
		(duplicate_pad_numbers_are_jumpers no)
		(fp_circle
			(center 0 0)
			(end -0.104648 0)
			(stroke
				(width 0.1016)
				(type default)
			)
			(fill no)
			(layer "B.SilkS")
		)
		(fp_poly
			(pts
				(xy 0.381 -0.889) (xy 0.381 0.889) (xy -0.381 0.889) (xy -0.381 -0.889)
			)
			(stroke
				(width 0)
				(type default)
			)
			(fill no)
			(layer "B.CrtYd")
		)
		(fp_line
			(start 0.508 1.016)
			(end 0.508 -1.016)
			(stroke
				(width 0.0254)
				(type default)
			)
			(layer "B.Fab")
		)
		(fp_line
			(start 0.508 -1.016)
			(end 0.254 -1.016)
			(stroke
				(width 0.0254)
				(type default)
			)
			(layer "B.Fab")
		)
		(fp_line
			(start 0.254 -1.016)
			(end -0.508 -1.016)
			(stroke
				(width 0.0254)
				(type default)
			)
			(layer "B.Fab")
		)
		(fp_line
			(start -0.508 1.016)
			(end 0.508 1.016)
			(stroke
				(width 0.0254)
				(type default)
			)
			(layer "B.Fab")
		)
		(fp_line
			(start -0.508 -1.016)
			(end -0.508 1.016)
			(stroke
				(width 0.0254)
				(type default)
			)
			(layer "B.Fab")
		)
		(pad "1" smd custom
			(at 0 -0.500126)
			(size 0.127 0.127)
			(layers "B.Cu" "B.Mask" "B.Paste")
			(net "VDD_3.3V")
			(options
				(clearance outline)
				(anchor circle)
			)
			(primitives
				(gr_poly
					(pts
						(xy -0.1778 0.254) (xy 0.1778 0.254) (xy 0.254 0.1778) (xy 0.254 -0.1778) (xy 0.1778 -0.254) (xy -0.1778 -0.254)
						(xy -0.254 -0.1778) (xy -0.254 0.1778)
					)
					(width 0)
					(fill yes)
				)
			)
		)
		(pad "2" smd custom
			(at 0 0.500126)
			(size 0.127 0.127)
			(layers "B.Cu" "B.Mask" "B.Paste")
			(net "GND")
			(options
				(clearance outline)
				(anchor circle)
			)
			(primitives
				(gr_poly
					(pts
						(xy -0.1778 0.254) (xy 0.1778 0.254) (xy 0.254 0.1778) (xy 0.254 -0.1778) (xy 0.1778 -0.254) (xy -0.1778 -0.254)
						(xy -0.254 -0.1778) (xy -0.254 0.1778)
					)
					(width 0)
					(fill yes)
				)
			)
		)
	)
	(footprint ""
		(layer "B.Cu")
		(at 51.237007 26.541984)
		(property "Reference" "C9"
			(at 0.933323 0.001016 270)
			(unlocked yes)
			(layer "B.SilkS")
			(effects
				(font
					(size 0.7874 0.5842)
					(thickness 0.127)
				)
				(justify mirror)
			)
		)
		(property "Value" ""
			(at 0 0 0)
			(layer "B.Fab")
			(effects
				(font
					(size 1.27 1.27)
				)
				(justify mirror)
			)
		)
		(duplicate_pad_numbers_are_jumpers no)
		(fp_circle
			(center 0 0)
			(end 0.104648 0)
			(stroke
				(width 0.1016)
				(type default)
			)
			(fill no)
			(layer "B.SilkS")
		)
		(fp_poly
			(pts
				(xy 0.381 -0.889) (xy 0.381 0.889) (xy -0.381 0.889) (xy -0.381 -0.889)
			)
			(stroke
				(width 0)
				(type default)
			)
			(fill no)
			(layer "B.CrtYd")
		)
		(fp_line
			(start -0.508 -1.016)
			(end -0.508 1.016)
			(stroke
				(width 0.0254)
				(type default)
			)
			(layer "B.Fab")
		)
		(fp_line
			(start -0.508 1.016)
			(end 0.508 1.016)
			(stroke
				(width 0.0254)
				(type default)
			)
			(layer "B.Fab")
		)
		(fp_line
			(start 0.254 -1.016)
			(end -0.508 -1.016)
			(stroke
				(width 0.0254)
				(type default)
			)
			(layer "B.Fab")
		)
		(fp_line
			(start 0.508 -1.016)
			(end 0.254 -1.016)
			(stroke
				(width 0.0254)
				(type default)
			)
			(layer "B.Fab")
		)
		(fp_line
			(start 0.508 1.016)
			(end 0.508 -1.016)
			(stroke
				(width 0.0254)
				(type default)
			)
			(layer "B.Fab")
		)
		(pad "1" smd custom
			(at 0 -0.500126 180)
			(size 0.127 0.127)
			(layers "B.Cu" "B.Mask" "B.Paste")
			(net "VDD_CORE")
			(options
				(clearance outline)
				(anchor circle)
			)
			(primitives
				(gr_poly
					(pts
						(xy -0.1778 0.254) (xy 0.1778 0.254) (xy 0.254 0.1778) (xy 0.254 -0.1778) (xy 0.1778 -0.254) (xy -0.1778 -0.254)
						(xy -0.254 -0.1778) (xy -0.254 0.1778)
					)
					(width 0)
					(fill yes)
				)
			)
		)
		(pad "2" smd custom
			(at 0 0.500126 180)
			(size 0.127 0.127)
			(layers "B.Cu" "B.Mask" "B.Paste")
			(net "GND")
			(options
				(clearance outline)
				(anchor circle)
			)
			(primitives
				(gr_poly
					(pts
						(xy -0.1778 0.254) (xy 0.1778 0.254) (xy 0.254 0.1778) (xy 0.254 -0.1778) (xy 0.1778 -0.254) (xy -0.1778 -0.254)
						(xy -0.254 -0.1778) (xy -0.254 0.1778)
					)
					(width 0)
					(fill yes)
				)
			)
		)
	)
	(footprint ""
		(layer "B.Cu")
		(at 84.250987 19.055994)
		(property "Reference" "V2_A-A08"
			(at 0 0 0)
			(layer "B.SilkS")
			(hide yes)
			(effects
				(font
					(size 1.27 1.27)
				)
				(justify mirror)
			)
		)
		(property "Value" ""
			(at 0 0 0)
			(layer "B.Fab")
			(effects
				(font
					(size 1.27 1.27)
				)
				(justify mirror)
			)
		)
		(duplicate_pad_numbers_are_jumpers no)
		(pad "1" thru_hole circle
			(at 0 0 180)
			(size 0.4572 0.4572)
			(drill 0.20574)
			(layers "*.Cu" "*.Mask")
			(remove_unused_layers no)
			(net "DDR0_32A_A8")
			(clearance 0.1143)
			(thermal_gap 0.1143)
		)
	)
)
